# T6G (Grand Teton) — schematic netlist excerpt (pin names and nets, part order shuffled) for the footprints in the layout excerpt that follows; sources: Cadence DE-HDL packaged netlist, KiCad conversion of 04192023_DAF0TMB3IC0_F0TG_MB_C_brd_V02_OCP.brd

C545  Q_CAP  1UF 4V 20% X6S  pkg 0201  page 279 : A = P0V9_CPU0_RT0_2A_2D ; B = GND
C7010  Q_CAP  100UF 4V 20% X6S  pkg C0805  page 279 : A = P0V9_CPU0_RT0_2A ; B = GND
C6625  Q_CAP_DIFFBUS  DIFF BUS_0.22UF 6.3V 20% X6S  pkg C0201  page 308 : \1\ = P5E_CPU0_P3_TX_BUF_C_DP<14> ; \2\ = P5E_CPU0_P3_TX_BUF_DP<14>
R3512  Q_RES  100K 1% EMPTY  pkg 0402LF  page 127 : A = P3V3_AUX ; B = FM_GPU_PWRGD

(kicad_pcb
	(version 20260206)
	(generator "pcbnew")
	(generator_version "10.0")
	(general
		(thickness 1.6)
		(legacy_teardrops no)
	)
	(paper "A4")
	(title_block
		(title "04192023_DAF0TMB3IC0_F0TG_MB_C_brd_V02_OCP.brd")
		(comment 1 "Grand Teton / footprints 6924-6927 of 8354")
	)
	(layers
		(0 "F.Cu" signal "TOP")
		(4 "In1.Cu" signal "GND")
		(6 "In2.Cu" signal "IN1")
		(8 "In3.Cu" signal "GND1")
		(10 "In4.Cu" signal "IN2")
		(12 "In5.Cu" signal "GND2")
		(14 "In6.Cu" signal "IN3")
		(16 "In7.Cu" signal "GND3")
		(18 "In8.Cu" signal "VCC")
		(20 "In9.Cu" signal "VCC1")
		(22 "In10.Cu" signal "GND4")
		(24 "In11.Cu" signal "IN4")
		(26 "In12.Cu" signal "GND5")
		(28 "In13.Cu" signal "IN5")
		(30 "In14.Cu" signal "GND6")
		(32 "In15.Cu" signal "IN6")
		(34 "In16.Cu" signal "GND7")
		(2 "B.Cu" signal "BOTTOM")
		(9 "F.Adhes" user "F.Adhesive")
		(11 "B.Adhes" user "B.Adhesive")
		(13 "F.Paste" user "Package Geometry/Pastemask Top")
		(15 "B.Paste" user "Package Geometry/Pastemask Bottom")
		(5 "F.SilkS" user "Ref Des/Silkscreen Top")
		(7 "B.SilkS" user "Ref Des/Silkscreen Bottom")
		(1 "F.Mask" user "Board Geometry/Soldermask Top")
		(3 "B.Mask" user "Board Geometry/Soldermask Bottom")
		(17 "Dwgs.User" user "User.Drawings")
		(19 "Cmts.User" user "User.Comments")
		(21 "Eco1.User" user "User.Eco1")
		(23 "Eco2.User" user "User.Eco2")
		(25 "Edge.Cuts" user "Board Geometry/Outline")
		(27 "Margin" user)
		(31 "F.CrtYd" user "Package Geometry/Place Bound Top")
		(29 "B.CrtYd" user "Package Geometry/Place Bound Bottom")
		(35 "F.Fab" user "Ref Des/Assembly Top")
		(33 "B.Fab" user "Ref Des/Assembly Bottom")
	)
	(footprint ""
		(layer "B.Cu")
		(at 316.578234 -395.148562 90)
		(property "Reference" "C545"
			(at 0 0 90)
			(layer "B.SilkS")
			(hide yes)
			(effects
				(font
					(size 1.27 1.27)
				)
				(justify mirror)
			)
		)
		(property "Value" ""
			(at 0 0 90)
			(layer "B.Fab")
			(effects
				(font
					(size 1.27 1.27)
				)
				(justify mirror)
			)
		)
		(duplicate_pad_numbers_are_jumpers no)
		(fp_line
			(start 0.299974 -0.150114)
			(end -0.299974 -0.150114)
			(stroke
				(width 0.1)
				(type default)
			)
			(layer "B.Fab")
		)
		(fp_line
			(start -0.299974 -0.150114)
			(end -0.299974 0.150114)
			(stroke
				(width 0.1)
				(type default)
			)
			(layer "B.Fab")
		)
		(fp_line
			(start 0.299974 0.150114)
			(end 0.299974 -0.150114)
			(stroke
				(width 0.1)
				(type default)
			)
			(layer "B.Fab")
		)
		(fp_line
			(start -0.299974 0.150114)
			(end 0.299974 0.150114)
			(stroke
				(width 0.1)
				(type default)
			)
			(layer "B.Fab")
		)
		(pad "1" smd rect
			(at 0.2667 0 270)
			(size 0.3048 0.381)
			(layers "B.Cu" "B.Mask" "B.Paste")
			(net "P0V9_CPU0_RT0_2A_2D")
		)
		(pad "2" smd rect
			(at -0.2667 0 270)
			(size 0.3048 0.381)
			(layers "B.Cu" "B.Mask" "B.Paste")
			(net "GND")
		)
	)
	(footprint ""
		(layer "B.Cu")
		(at 416.200082 -416.899344 90)
		(property "Reference" "C6625"
			(at 0 0 90)
			(layer "B.SilkS")
			(hide yes)
			(effects
				(font
					(size 1.27 1.27)
				)
				(justify mirror)
			)
		)
		(property "Value" ""
			(at 0 0 90)
			(layer "B.Fab")
			(effects
				(font
					(size 1.27 1.27)
				)
				(justify mirror)
			)
		)
		(duplicate_pad_numbers_are_jumpers no)
		(fp_line
			(start 0.299974 -0.150114)
			(end -0.299974 -0.150114)
			(stroke
				(width 0.1)
				(type default)
			)
			(layer "B.Fab")
		)
		(fp_line
			(start -0.299974 -0.150114)
			(end -0.299974 0.150114)
			(stroke
				(width 0.1)
				(type default)
			)
			(layer "B.Fab")
		)
		(fp_line
			(start 0.299974 0.150114)
			(end 0.299974 -0.150114)
			(stroke
				(width 0.1)
				(type default)
			)
			(layer "B.Fab")
		)
		(fp_line
			(start -0.299974 0.150114)
			(end 0.299974 0.150114)
			(stroke
				(width 0.1)
				(type default)
			)
			(layer "B.Fab")
		)
		(pad "1" smd rect
			(at 0.2667 0 270)
			(size 0.3048 0.381)
			(layers "B.Cu" "B.Mask" "B.Paste")
			(net "P5E_CPU0_P3_TX_BUF_C_DP<14>")
		)
		(pad "2" smd rect
			(at -0.2667 0 270)
			(size 0.3048 0.381)
			(layers "B.Cu" "B.Mask" "B.Paste")
			(net "P5E_CPU0_P3_TX_BUF_DP<14>")
		)
	)
	(footprint ""
		(layer "B.Cu")
		(at 301.562008 -389.444738)
		(property "Reference" "C7010"
			(at 0 0 0)
			(layer "B.SilkS")
			(hide yes)
			(effects
				(font
					(size 1.27 1.27)
				)
				(justify mirror)
			)
		)
		(property "Value" ""
			(at 0 0 0)
			(layer "B.Fab")
			(effects
				(font
					(size 1.27 1.27)
				)
				(justify mirror)
			)
		)
		(duplicate_pad_numbers_are_jumpers no)
		(fp_line
			(start -1.524 -0.762)
			(end -1.524 0.762)
			(stroke
				(width 0.1524)
				(type default)
			)
			(layer "B.SilkS")
		)
		(fp_line
			(start -1.524 0.762)
			(end 1.524 0.762)
			(stroke
				(width 0.1524)
				(type default)
			)
			(layer "B.SilkS")
		)
		(fp_line
			(start 1.524 -0.762)
			(end -1.524 -0.762)
			(stroke
				(width 0.1524)
				(type default)
			)
			(layer "B.SilkS")
		)
		(fp_line
			(start 1.524 0.762)
			(end 1.524 -0.762)
			(stroke
				(width 0.1524)
				(type default)
			)
			(layer "B.SilkS")
		)
		(fp_line
			(start -1.1049 -0.724916)
			(end 1.1049 -0.724916)
			(stroke
				(width 0.1)
				(type default)
			)
			(layer "B.Fab")
		)
		(fp_line
			(start -1.1049 0.724916)
			(end -1.1049 -0.724916)
			(stroke
				(width 0.1)
				(type default)
			)
			(layer "B.Fab")
		)
		(fp_line
			(start 1.1049 -0.724916)
			(end 1.1049 0.724916)
			(stroke
				(width 0.1)
				(type default)
			)
			(layer "B.Fab")
		)
		(fp_line
			(start 1.1049 0.724916)
			(end -1.1049 0.724916)
			(stroke
				(width 0.1)
				(type default)
			)
			(layer "B.Fab")
		)
		(pad "1" smd rect
			(at 0.889 0)
			(size 1.016 1.27)
			(layers "B.Cu" "B.Mask" "B.Paste")
			(net "P0V9_CPU0_RT0_2A")
		)
		(pad "2" smd rect
			(at -0.889 0)
			(size 1.016 1.27)
			(layers "B.Cu" "B.Mask" "B.Paste")
			(net "GND")
		)
	)
	(footprint ""
		(layer "B.Cu")
		(at 52.74564 -426.003212 90)
		(property "Reference" "R3512"
			(at 0 0 90)
			(layer "B.SilkS")
			(hide yes)
			(effects
				(font
					(size 1.27 1.27)
				)
				(justify mirror)
			)
		)
		(property "Value" ""
			(at 0 0 90)
			(layer "B.Fab")
			(effects
				(font
					(size 1.27 1.27)
				)
				(justify mirror)
			)
		)
		(duplicate_pad_numbers_are_jumpers no)
		(fp_line
			(start 0.7874 -0.4064)
			(end -0.7874 -0.4064)
			(stroke
				(width 0.1524)
				(type default)
			)
			(layer "B.SilkS")
		)
		(fp_line
			(start -0.7874 -0.4064)
			(end -0.7874 0.4064)
			(stroke
				(width 0.1524)
				(type default)
			)
			(layer "B.SilkS")
		)
		(fp_line
			(start 0.7874 0.4064)
			(end 0.7874 -0.4064)
			(stroke
				(width 0.1524)
				(type default)
			)
			(layer "B.SilkS")
		)
		(fp_line
			(start -0.7874 0.4064)
			(end 0.7874 0.4064)
			(stroke
				(width 0.1524)
				(type default)
			)
			(layer "B.SilkS")
		)
		(fp_line
			(start 0.67945 -0.305054)
			(end 0.12065 -0.305054)
			(stroke
				(width 0.1)
				(type default)
			)
			(layer "B.Fab")
		)
		(fp_line
			(start 0.12065 -0.305054)
			(end 0.12065 -0.2794)
			(stroke
				(width 0.1)
				(type default)
			)
			(layer "B.Fab")
		)
		(fp_line
			(start -0.12065 -0.3048)
			(end -0.67945 -0.3048)
			(stroke
				(width 0.1)
				(type default)
			)
			(layer "B.Fab")
		)
		(fp_line
			(start -0.67945 -0.3048)
			(end -0.67945 0.3048)
			(stroke
				(width 0.1)
				(type default)
			)
			(layer "B.Fab")
		)
		(fp_line
			(start 0.12065 -0.2794)
			(end -0.12065 -0.2794)
			(stroke
				(width 0.1)
				(type default)
			)
			(layer "B.Fab")
		)
		(fp_line
			(start -0.12065 -0.2794)
			(end -0.12065 -0.3048)
			(stroke
				(width 0.1)
				(type default)
			)
			(layer "B.Fab")
		)
		(fp_line
			(start 0.12065 0.2794)
			(end 0.12065 0.3048)
			(stroke
				(width 0.1)
				(type default)
			)
			(layer "B.Fab")
		)
		(fp_line
			(start -0.120396 0.2794)
			(end 0.12065 0.2794)
			(stroke
				(width 0.1)
				(type default)
			)
			(layer "B.Fab")
		)
		(fp_line
			(start 0.67945 0.3048)
			(end 0.67945 -0.305054)
			(stroke
				(width 0.1)
				(type default)
			)
			(layer "B.Fab")
		)
		(fp_line
			(start 0.12065 0.3048)
			(end 0.67945 0.3048)
			(stroke
				(width 0.1)
				(type default)
			)
			(layer "B.Fab")
		)
		(fp_line
			(start -0.120396 0.3048)
			(end -0.120396 0.2794)
			(stroke
				(width 0.1)
				(type default)
			)
			(layer "B.Fab")
		)
		(fp_line
			(start -0.67945 0.3048)
			(end -0.120396 0.3048)
			(stroke
				(width 0.1)
				(type default)
			)
			(layer "B.Fab")
		)
		(pad "1" smd circle
			(at 0.40005 0 270)
			(size 0 0)
			(layers "B.Cu" "B.Mask" "B.Paste")
			(net "P3V3_AUX")
		)
		(pad "2" smd circle
			(at -0.40005 0 270)
			(size 0 0)
			(layers "B.Cu" "B.Mask" "B.Paste")
			(net "FM_GPU_PWRGD")
		)
	)
)
